# S9S_MB_2U (Grand Teton) — schematic netlist excerpt (pin names and nets, part order shuffled) for the footprints in the layout excerpt that follows; sources: Cadence DE-HDL packaged netlist, KiCad conversion of 03242023_DA0F0TMBIJ0_F0T_Motherboard_J_brd_V01_OCP.brd

PR3855  Q_RES  71.5K 1% EMPTY  pkg 0402LF  page 163 : A = P3V3_OCP_MODE_2 ; B = GND
PC2098  Q_CAP  1UF 25V 10% EMPTY  pkg C0402  page 162 : A = P12V_OCP_VCC_2 ; B = GND

(kicad_pcb
	(version 20260206)
	(generator "pcbnew")
	(generator_version "10.0")
	(general
		(thickness 1.6)
		(legacy_teardrops no)
	)
	(paper "A4")
	(title_block
		(title "03242023_DA0F0TMBIJ0_F0T_Motherboard_J_brd_V01_OCP.brd")
		(comment 1 "Grand Teton / footprints 1604-1605 of 6105")
	)
	(layers
		(0 "F.Cu" signal "TOP")
		(4 "In1.Cu" signal "GND")
		(6 "In2.Cu" signal "IN1")
		(8 "In3.Cu" signal "GND1")
		(10 "In4.Cu" signal "IN2")
		(12 "In5.Cu" signal "GND2")
		(14 "In6.Cu" signal "IN3")
		(16 "In7.Cu" signal "GND3")
		(18 "In8.Cu" signal "VCC")
		(20 "In9.Cu" signal "VCC1")
		(22 "In10.Cu" signal "GND4")
		(24 "In11.Cu" signal "IN4")
		(26 "In12.Cu" signal "GND5")
		(28 "In13.Cu" signal "IN5")
		(30 "In14.Cu" signal "GND6")
		(32 "In15.Cu" signal "IN6")
		(34 "In16.Cu" signal "GND7")
		(2 "B.Cu" signal "BOTTOM")
		(9 "F.Adhes" user "F.Adhesive")
		(11 "B.Adhes" user "B.Adhesive")
		(13 "F.Paste" user "Package Geometry/Pastemask Top")
		(15 "B.Paste" user "Package Geometry/Pastemask Bottom")
		(5 "F.SilkS" user "Ref Des/Silkscreen Top")
		(7 "B.SilkS" user "Ref Des/Silkscreen Bottom")
		(1 "F.Mask" user "Board Geometry/Soldermask Top")
		(3 "B.Mask" user "Board Geometry/Soldermask Bottom")
		(17 "Dwgs.User" user "User.Drawings")
		(19 "Cmts.User" user "User.Comments")
		(21 "Eco1.User" user "User.Eco1")
		(23 "Eco2.User" user "User.Eco2")
		(25 "Edge.Cuts" user "Board Geometry/Outline")
		(27 "Margin" user)
		(31 "F.CrtYd" user "Package Geometry/Place Bound Top")
		(29 "B.CrtYd" user "Package Geometry/Place Bound Bottom")
		(35 "F.Fab" user "Ref Des/Assembly Top")
		(33 "B.Fab" user "Ref Des/Assembly Bottom")
	)
	(footprint ""
		(layer "F.Cu")
		(at 77.128878 -23.308818 180)
		(property "Reference" "PC2098"
			(at 0 0 180)
			(layer "F.SilkS")
			(hide yes)
			(effects
				(font
					(size 1.27 1.27)
				)
			)
		)
		(property "Value" ""
			(at 0 0 180)
			(layer "F.Fab")
			(effects
				(font
					(size 1.27 1.27)
				)
			)
		)
		(duplicate_pad_numbers_are_jumpers no)
		(fp_line
			(start 0.7874 0.4064)
			(end -0.7874 0.4064)
			(stroke
				(width 0.1524)
				(type default)
			)
			(layer "F.SilkS")
		)
		(fp_line
			(start 0.7874 -0.4064)
			(end 0.7874 0.4064)
			(stroke
				(width 0.1524)
				(type default)
			)
			(layer "F.SilkS")
		)
		(fp_line
			(start -0.7874 0.4064)
			(end -0.7874 -0.4064)
			(stroke
				(width 0.1524)
				(type default)
			)
			(layer "F.SilkS")
		)
		(fp_line
			(start -0.7874 -0.4064)
			(end 0.7874 -0.4064)
			(stroke
				(width 0.1524)
				(type default)
			)
			(layer "F.SilkS")
		)
		(fp_line
			(start 0.67945 0.3048)
			(end 0.120396 0.3048)
			(stroke
				(width 0.1)
				(type default)
			)
			(layer "F.Fab")
		)
		(fp_line
			(start 0.67945 -0.3048)
			(end 0.67945 0.3048)
			(stroke
				(width 0.1)
				(type default)
			)
			(layer "F.Fab")
		)
		(fp_line
			(start 0.12065 -0.2794)
			(end 0.12065 -0.3048)
			(stroke
				(width 0.1)
				(type default)
			)
			(layer "F.Fab")
		)
		(fp_line
			(start 0.12065 -0.3048)
			(end 0.67945 -0.3048)
			(stroke
				(width 0.1)
				(type default)
			)
			(layer "F.Fab")
		)
		(fp_line
			(start 0.120396 0.3048)
			(end 0.120396 0.2794)
			(stroke
				(width 0.1)
				(type default)
			)
			(layer "F.Fab")
		)
		(fp_line
			(start 0.120396 0.2794)
			(end -0.12065 0.2794)
			(stroke
				(width 0.1)
				(type default)
			)
			(layer "F.Fab")
		)
		(fp_line
			(start -0.12065 0.3048)
			(end -0.67945 0.3048)
			(stroke
				(width 0.1)
				(type default)
			)
			(layer "F.Fab")
		)
		(fp_line
			(start -0.12065 0.2794)
			(end -0.12065 0.3048)
			(stroke
				(width 0.1)
				(type default)
			)
			(layer "F.Fab")
		)
		(fp_line
			(start -0.12065 -0.2794)
			(end 0.12065 -0.2794)
			(stroke
				(width 0.1)
				(type default)
			)
			(layer "F.Fab")
		)
		(fp_line
			(start -0.12065 -0.305054)
			(end -0.12065 -0.2794)
			(stroke
				(width 0.1)
				(type default)
			)
			(layer "F.Fab")
		)
		(fp_line
			(start -0.67945 0.3048)
			(end -0.67945 -0.305054)
			(stroke
				(width 0.1)
				(type default)
			)
			(layer "F.Fab")
		)
		(fp_line
			(start -0.67945 -0.305054)
			(end -0.12065 -0.305054)
			(stroke
				(width 0.1)
				(type default)
			)
			(layer "F.Fab")
		)
		(pad "1" smd circle
			(at -0.40005 0 180)
			(size 0 0)
			(layers "F.Cu" "F.Mask" "F.Paste")
			(net "P12V_OCP_VCC_2")
		)
		(pad "2" smd circle
			(at 0.40005 0 180)
			(size 0 0)
			(layers "F.Cu" "F.Mask" "F.Paste")
			(net "GND")
		)
	)
	(footprint ""
		(layer "F.Cu")
		(at 70.93712 -53.543708)
		(property "Reference" "PR3855"
			(at 0 0 0)
			(layer "F.SilkS")
			(hide yes)
			(effects
				(font
					(size 1.27 1.27)
				)
			)
		)
		(property "Value" ""
			(at 0 0 0)
			(layer "F.Fab")
			(effects
				(font
					(size 1.27 1.27)
				)
			)
		)
		(duplicate_pad_numbers_are_jumpers no)
		(fp_line
			(start -0.7874 -0.4064)
			(end 0.7874 -0.4064)
			(stroke
				(width 0.1524)
				(type default)
			)
			(layer "F.SilkS")
		)
		(fp_line
			(start -0.7874 0.4064)
			(end -0.7874 -0.4064)
			(stroke
				(width 0.1524)
				(type default)
			)
			(layer "F.SilkS")
		)
		(fp_line
			(start 0.7874 -0.4064)
			(end 0.7874 0.4064)
			(stroke
				(width 0.1524)
				(type default)
			)
			(layer "F.SilkS")
		)
		(fp_line
			(start 0.7874 0.4064)
			(end -0.7874 0.4064)
			(stroke
				(width 0.1524)
				(type default)
			)
			(layer "F.SilkS")
		)
		(fp_line
			(start -0.67945 -0.305054)
			(end -0.12065 -0.305054)
			(stroke
				(width 0.1)
				(type default)
			)
			(layer "F.Fab")
		)
		(fp_line
			(start -0.67945 0.3048)
			(end -0.67945 -0.305054)
			(stroke
				(width 0.1)
				(type default)
			)
			(layer "F.Fab")
		)
		(fp_line
			(start -0.12065 -0.305054)
			(end -0.12065 -0.2794)
			(stroke
				(width 0.1)
				(type default)
			)
			(layer "F.Fab")
		)
		(fp_line
			(start -0.12065 -0.2794)
			(end 0.12065 -0.2794)
			(stroke
				(width 0.1)
				(type default)
			)
			(layer "F.Fab")
		)
		(fp_line
			(start -0.12065 0.2794)
			(end -0.12065 0.3048)
			(stroke
				(width 0.1)
				(type default)
			)
			(layer "F.Fab")
		)
		(fp_line
			(start -0.12065 0.3048)
			(end -0.67945 0.3048)
			(stroke
				(width 0.1)
				(type default)
			)
			(layer "F.Fab")
		)
		(fp_line
			(start 0.120396 0.2794)
			(end -0.12065 0.2794)
			(stroke
				(width 0.1)
				(type default)
			)
			(layer "F.Fab")
		)
		(fp_line
			(start 0.120396 0.3048)
			(end 0.120396 0.2794)
			(stroke
				(width 0.1)
				(type default)
			)
			(layer "F.Fab")
		)
		(fp_line
			(start 0.12065 -0.3048)
			(end 0.67945 -0.3048)
			(stroke
				(width 0.1)
				(type default)
			)
			(layer "F.Fab")
		)
		(fp_line
			(start 0.12065 -0.2794)
			(end 0.12065 -0.3048)
			(stroke
				(width 0.1)
				(type default)
			)
			(layer "F.Fab")
		)
		(fp_line
			(start 0.67945 -0.3048)
			(end 0.67945 0.3048)
			(stroke
				(width 0.1)
				(type default)
			)
			(layer "F.Fab")
		)
		(fp_line
			(start 0.67945 0.3048)
			(end 0.120396 0.3048)
			(stroke
				(width 0.1)
				(type default)
			)
			(layer "F.Fab")
		)
		(pad "1" smd circle
			(at -0.40005 0)
			(size 0 0)
			(layers "F.Cu" "F.Mask" "F.Paste")
			(net "P3V3_OCP_MODE_2")
		)
		(pad "2" smd circle
			(at 0.40005 0)
			(size 0 0)
			(layers "F.Cu" "F.Mask" "F.Paste")
			(net "GND")
		)
	)
)
